(kicad_pcb
	(version 20260206)
	(generator "pcbnew")
	(generator_version "10.0")
	(general
		(thickness 1.6)
		(legacy_teardrops no)
	)
	(paper "A4")
	(title_block
		(title "panther-plus-userver — 13130-1b_20150205.brd")
		(comment 1 "Honey Badger (Wiwynn) / footprints 1127-1133 of 1509")
	)
	(layers
		(0 "F.Cu" signal "TOP")
		(4 "In1.Cu" signal "L2")
		(6 "In2.Cu" signal "L3")
		(8 "In3.Cu" signal "L4")
		(10 "In4.Cu" signal "L5")
		(12 "In5.Cu" signal "L6")
		(14 "In6.Cu" signal "L7")
		(16 "In7.Cu" signal "L8")
		(18 "In8.Cu" signal "L9")
		(20 "In9.Cu" signal "L10")
		(22 "In10.Cu" signal "L11")
		(2 "B.Cu" signal "BOTTOM")
		(9 "F.Adhes" user "F.Adhesive")
		(11 "B.Adhes" user "B.Adhesive")
		(13 "F.Paste" user "Package Geometry/Pastemask Top")
		(15 "B.Paste" user "Package Geometry/Pastemask Bottom")
		(5 "F.SilkS" user "Ref Des/Silkscreen Top")
		(7 "B.SilkS" user "Ref Des/Silkscreen Bottom")
		(1 "F.Mask" user "Board Geometry/Soldermask Top")
		(3 "B.Mask" user "Board Geometry/Soldermask Bottom")
		(17 "Dwgs.User" user "User.Drawings")
		(19 "Cmts.User" user "User.Comments")
		(21 "Eco1.User" user "User.Eco1")
		(23 "Eco2.User" user "User.Eco2")
		(25 "Edge.Cuts" user "Board Geometry/Outline")
		(27 "Margin" user)
		(31 "F.CrtYd" user "Package Geometry/Place Bound Top")
		(29 "B.CrtYd" user "Package Geometry/Place Bound Bottom")
		(35 "F.Fab" user "Ref Des/Assembly Top")
		(33 "B.Fab" user "Ref Des/Assembly Bottom")
	)
	(footprint ""
		(layer "B.Cu")
		(at 118.1608 -4.445 -90)
		(property "Reference" "U41"
			(at 0 0 90)
			(layer "B.SilkS")
			(hide yes)
			(effects
				(font
					(size 1.27 1.27)
				)
				(justify mirror)
			)
		)
		(property "Value" "SNLVC1G126DCKR-GP"
			(at 0 -8.0772 270)
			(unlocked yes)
			(layer "B.Fab")
			(hide yes)
			(effects
				(font
					(size 1.016 1.016)
					(thickness 0.1524)
				)
				(justify mirror)
			)
		)
		(property "Device Type" "SC70-5H44"
			(at 0 -9.6012 270)
			(unlocked yes)
			(layer "B.Fab")
			(hide yes)
			(effects
				(font
					(size 1.016 1.016)
					(thickness 0.1524)
				)
				(justify mirror)
			)
		)
		(duplicate_pad_numbers_are_jumpers no)
		(fp_line
			(start -1.0033 0.3302)
			(end 1.0033 0.3302)
			(stroke
				(width 0.1524)
				(type default)
			)
			(layer "B.SilkS")
		)
		(fp_line
			(start 1.0033 0.3302)
			(end 1.0033 -0.3302)
			(stroke
				(width 0.1524)
				(type default)
			)
			(layer "B.SilkS")
		)
		(fp_line
			(start -1.0033 -0.3302)
			(end -1.0033 0.3302)
			(stroke
				(width 0.1524)
				(type default)
			)
			(layer "B.SilkS")
		)
		(fp_line
			(start 1.0033 -0.3302)
			(end -1.0033 -0.3302)
			(stroke
				(width 0.1524)
				(type default)
			)
			(layer "B.SilkS")
		)
		(fp_poly
			(pts
				(xy 1.0033 1.4859) (xy 1.0033 0.8001) (xy 1.1811 0.8001) (xy 1.1811 -0.8001) (xy 1.0033 -0.8001)
				(xy 1.0033 -1.4859) (xy -1.0033 -1.4859) (xy -1.0033 -0.8001) (xy -1.1811 -0.8001) (xy -1.1811 0.8001)
				(xy -1.0033 0.8001) (xy -1.0033 1.4859) (xy -0.2921 1.4859) (xy -0.2921 0.8001) (xy 0.2921 0.8001)
				(xy 0.2921 1.4859)
			)
			(stroke
				(width 0)
				(type default)
			)
			(fill no)
			(layer "B.CrtYd")
		)
		(fp_poly
			(pts
				(xy 1.0033 1.4859) (xy 1.0033 0.8001) (xy 1.1811 0.8001) (xy 1.1811 -0.8001) (xy 1.0033 -0.8001)
				(xy 1.0033 -1.4859) (xy -1.0033 -1.4859) (xy -1.0033 -0.8001) (xy -1.1811 -0.8001) (xy -1.1811 0.8001)
				(xy -1.0033 0.8001) (xy -1.0033 1.4859) (xy -0.2921 1.4859) (xy -0.2921 0.8001) (xy 0.2921 0.8001)
				(xy 0.2921 1.4859)
			)
			(stroke
				(width 0)
				(type default)
			)
			(fill no)
			(layer "B.Fab")
		)
		(pad "1" smd rect
			(at -0.65024 -0.93472 90)
			(size 0.3556 0.762)
			(layers "B.Cu" "B.Mask" "B.Paste")
			(net "P3V3")
		)
		(pad "2" smd rect
			(at 0 -0.93472 90)
			(size 0.3556 0.762)
			(layers "B.Cu" "B.Mask" "B.Paste")
			(net "CLK_GEN_PG")
		)
		(pad "3" smd rect
			(at 0.65024 -0.93472 90)
			(size 0.3556 0.762)
			(layers "B.Cu" "B.Mask" "B.Paste")
			(net "GND")
		)
		(pad "4" smd rect
			(at 0.65024 0.93472 90)
			(size 0.3556 0.762)
			(layers "B.Cu" "B.Mask" "B.Paste")
			(net "POWER_GOOD")
		)
		(pad "5" smd rect
			(at -0.65024 0.93472 90)
			(size 0.3556 0.762)
			(layers "B.Cu" "B.Mask" "B.Paste")
			(net "P3V3")
		)
	)
	(footprint ""
		(layer "B.Cu")
		(at 103.251 -51.451002 180)
		(property "Reference" "C128"
			(at 0 0 0)
			(layer "B.SilkS")
			(hide yes)
			(effects
				(font
					(size 1.27 1.27)
				)
				(justify mirror)
			)
		)
		(property "Value" "SC1U10V2KX-1GP"
			(at -1.1811 -2.7051 180)
			(unlocked yes)
			(layer "B.Fab")
			(hide yes)
			(effects
				(font
					(size 1.016 1.016)
					(thickness 0.1524)
				)
				(justify mirror)
			)
		)
		(property "Device Type" "C402H22"
			(at -1.1811 -4.2291 180)
			(unlocked yes)
			(layer "B.Fab")
			(hide yes)
			(effects
				(font
					(size 1.016 1.016)
					(thickness 0.1524)
				)
				(justify mirror)
			)
		)
		(duplicate_pad_numbers_are_jumpers no)
		(fp_rect
			(start 0.381 0.7366)
			(end -0.381 -0.7366)
			(stroke
				(width 0)
				(type default)
			)
			(fill no)
			(layer "B.CrtYd")
		)
		(fp_rect
			(start 0.381 0.7366)
			(end -0.381 -0.7366)
			(stroke
				(width 0)
				(type default)
			)
			(fill no)
			(layer "B.Fab")
		)
		(pad "1" smd custom
			(at 0 -0.4572)
			(size 0.1143 0.1143)
			(layers "B.Cu" "B.Mask" "B.Paste")
			(net "PV_VDDR")
			(options
				(clearance outline)
				(anchor circle)
			)
			(primitives
				(gr_poly
					(pts
						(arc
							(start -0.254 0.1778)
							(mid -0.239121 0.213721)
							(end -0.2032 0.2286)
						)
						(arc
							(start 0.2032 0.2286)
							(mid 0.239121 0.213721)
							(end 0.254 0.1778)
						)
						(arc
							(start 0.254 -0.1778)
							(mid 0.239121 -0.213721)
							(end 0.2032 -0.2286)
						)
						(arc
							(start -0.2032 -0.2286)
							(mid -0.239121 -0.213721)
							(end -0.254 -0.1778)
						)
					)
					(width 0)
					(fill yes)
				)
			)
		)
		(pad "2" smd custom
			(at 0 0.4572)
			(size 0.1143 0.1143)
			(layers "B.Cu" "B.Mask" "B.Paste")
			(net "GND")
			(options
				(clearance outline)
				(anchor circle)
			)
			(primitives
				(gr_poly
					(pts
						(arc
							(start -0.254 0.1778)
							(mid -0.239121 0.213721)
							(end -0.2032 0.2286)
						)
						(arc
							(start 0.2032 0.2286)
							(mid 0.239121 0.213721)
							(end 0.254 0.1778)
						)
						(arc
							(start 0.254 -0.1778)
							(mid 0.239121 -0.213721)
							(end 0.2032 -0.2286)
						)
						(arc
							(start -0.2032 -0.2286)
							(mid -0.239121 -0.213721)
							(end -0.254 -0.1778)
						)
					)
					(width 0)
					(fill yes)
				)
			)
		)
	)
	(footprint ""
		(layer "B.Cu")
		(at 15.875 -66.4718 90)
		(property "Reference" "C177"
			(at 0 0 90)
			(layer "B.SilkS")
			(hide yes)
			(effects
				(font
					(size 1.27 1.27)
				)
				(justify mirror)
			)
		)
		(property "Value" "SCD1U16V2KX-3GP"
			(at -1.8923 -1.2065 90)
			(unlocked yes)
			(layer "B.Fab")
			(hide yes)
			(effects
				(font
					(size 1.016 1.016)
					(thickness 0.1524)
				)
				(justify mirror)
			)
		)
		(property "Device Type" "C402H22"
			(at -1.8923 -2.7305 90)
			(unlocked yes)
			(layer "B.Fab")
			(hide yes)
			(effects
				(font
					(size 1.016 1.016)
					(thickness 0.1524)
				)
				(justify mirror)
			)
		)
		(duplicate_pad_numbers_are_jumpers no)
		(fp_rect
			(start 0.381 0.7366)
			(end -0.381 -0.7366)
			(stroke
				(width 0)
				(type default)
			)
			(fill no)
			(layer "B.CrtYd")
		)
		(fp_rect
			(start 0.381 0.7366)
			(end -0.381 -0.7366)
			(stroke
				(width 0)
				(type default)
			)
			(fill no)
			(layer "B.Fab")
		)
		(pad "1" smd custom
			(at 0 -0.4572 270)
			(size 0.1143 0.1143)
			(layers "B.Cu" "B.Mask" "B.Paste")
			(net "P3V3")
			(options
				(clearance outline)
				(anchor circle)
			)
			(primitives
				(gr_poly
					(pts
						(arc
							(start -0.254 0.1778)
							(mid -0.239121 0.213721)
							(end -0.2032 0.2286)
						)
						(arc
							(start 0.2032 0.2286)
							(mid 0.239121 0.213721)
							(end 0.254 0.1778)
						)
						(arc
							(start 0.254 -0.1778)
							(mid 0.239121 -0.213721)
							(end 0.2032 -0.2286)
						)
						(arc
							(start -0.2032 -0.2286)
							(mid -0.239121 -0.213721)
							(end -0.254 -0.1778)
						)
					)
					(width 0)
					(fill yes)
				)
			)
		)
		(pad "2" smd custom
			(at 0 0.4572 270)
			(size 0.1143 0.1143)
			(layers "B.Cu" "B.Mask" "B.Paste")
			(net "GND")
			(options
				(clearance outline)
				(anchor circle)
			)
			(primitives
				(gr_poly
					(pts
						(arc
							(start -0.254 0.1778)
							(mid -0.239121 0.213721)
							(end -0.2032 0.2286)
						)
						(arc
							(start 0.2032 0.2286)
							(mid 0.239121 0.213721)
							(end 0.254 0.1778)
						)
						(arc
							(start 0.254 -0.1778)
							(mid 0.239121 -0.213721)
							(end 0.2032 -0.2286)
						)
						(arc
							(start -0.2032 -0.2286)
							(mid -0.239121 -0.213721)
							(end -0.254 -0.1778)
						)
					)
					(width 0)
					(fill yes)
				)
			)
		)
	)
	(footprint ""
		(layer "B.Cu")
		(at 78.486 -23.6474)
		(property "Reference" "PR220"
			(at 0 0 0)
			(layer "B.SilkS")
			(hide yes)
			(effects
				(font
					(size 1.27 1.27)
				)
				(justify mirror)
			)
		)
		(property "Value" "0R2J-2-GP"
			(at -0.064008 -3.993896 0)
			(unlocked yes)
			(layer "B.Fab")
			(hide yes)
			(effects
				(font
					(size 1.016 1.016)
					(thickness 0.1524)
				)
				(justify mirror)
			)
		)
		(property "Device Type" "R402H16"
			(at -0.064008 -5.517896 0)
			(unlocked yes)
			(layer "B.Fab")
			(hide yes)
			(effects
				(font
					(size 1.016 1.016)
					(thickness 0.1524)
				)
				(justify mirror)
			)
		)
		(duplicate_pad_numbers_are_jumpers no)
		(fp_rect
			(start 0.381 0.8382)
			(end -0.381 -0.8382)
			(stroke
				(width 0)
				(type default)
			)
			(fill no)
			(layer "B.CrtYd")
		)
		(fp_rect
			(start 0.381 0.8382)
			(end -0.381 -0.8382)
			(stroke
				(width 0)
				(type default)
			)
			(fill no)
			(layer "B.Fab")
		)
		(pad "1" smd custom
			(at 0 -0.4318 180)
			(size 0.127 0.127)
			(layers "B.Cu" "B.Mask" "B.Paste")
			(net "P3V3_STBY")
			(options
				(clearance outline)
				(anchor circle)
			)
			(primitives
				(gr_poly
					(pts
						(arc
							(start -0.2032 0.2794)
							(mid -0.239121 0.264521)
							(end -0.254 0.2286)
						)
						(arc
							(start -0.254 -0.2286)
							(mid -0.239121 -0.264521)
							(end -0.2032 -0.2794)
						)
						(arc
							(start 0.2032 -0.2794)
							(mid 0.239121 -0.264521)
							(end 0.254 -0.2286)
						)
						(arc
							(start 0.254 0.2286)
							(mid 0.239121 0.264521)
							(end 0.2032 0.2794)
						)
					)
					(width 0)
					(fill yes)
				)
			)
		)
		(pad "2" smd custom
			(at 0 0.4318 180)
			(size 0.127 0.127)
			(layers "B.Cu" "B.Mask" "B.Paste")
			(net "TPS74801_1V35_BIAS")
			(options
				(clearance outline)
				(anchor circle)
			)
			(primitives
				(gr_poly
					(pts
						(arc
							(start -0.2032 0.2794)
							(mid -0.239121 0.264521)
							(end -0.254 0.2286)
						)
						(arc
							(start -0.254 -0.2286)
							(mid -0.239121 -0.264521)
							(end -0.2032 -0.2794)
						)
						(arc
							(start 0.2032 -0.2794)
							(mid 0.239121 -0.264521)
							(end 0.254 -0.2286)
						)
						(arc
							(start 0.254 0.2286)
							(mid 0.239121 0.264521)
							(end 0.2032 0.2794)
						)
					)
					(width 0)
					(fill yes)
				)
			)
		)
	)
	(footprint ""
		(layer "B.Cu")
		(at 85.344 -27.686 180)
		(property "Reference" "R372"
			(at 0 0 0)
			(layer "B.SilkS")
			(hide yes)
			(effects
				(font
					(size 1.27 1.27)
				)
				(justify mirror)
			)
		)
		(property "Value" "402R2F-GP"
			(at -0.064008 -3.993896 180)
			(unlocked yes)
			(layer "B.Fab")
			(hide yes)
			(effects
				(font
					(size 1.016 1.016)
					(thickness 0.1524)
				)
				(justify mirror)
			)
		)
		(property "Device Type" "R402H16"
			(at -0.064008 -5.517896 180)
			(unlocked yes)
			(layer "B.Fab")
			(hide yes)
			(effects
				(font
					(size 1.016 1.016)
					(thickness 0.1524)
				)
				(justify mirror)
			)
		)
		(duplicate_pad_numbers_are_jumpers no)
		(fp_rect
			(start 0.381 0.8382)
			(end -0.381 -0.8382)
			(stroke
				(width 0)
				(type default)
			)
			(fill no)
			(layer "B.CrtYd")
		)
		(fp_rect
			(start 0.381 0.8382)
			(end -0.381 -0.8382)
			(stroke
				(width 0)
				(type default)
			)
			(fill no)
			(layer "B.Fab")
		)
		(pad "1" smd custom
			(at 0 -0.4318)
			(size 0.127 0.127)
			(layers "B.Cu" "B.Mask" "B.Paste")
			(net "GBE_OBSP")
			(options
				(clearance outline)
				(anchor circle)
			)
			(primitives
				(gr_poly
					(pts
						(arc
							(start -0.2032 0.2794)
							(mid -0.239121 0.264521)
							(end -0.254 0.2286)
						)
						(arc
							(start -0.254 -0.2286)
							(mid -0.239121 -0.264521)
							(end -0.2032 -0.2794)
						)
						(arc
							(start 0.2032 -0.2794)
							(mid 0.239121 -0.264521)
							(end 0.254 -0.2286)
						)
						(arc
							(start 0.254 0.2286)
							(mid 0.239121 0.264521)
							(end 0.2032 0.2794)
						)
					)
					(width 0)
					(fill yes)
				)
			)
		)
		(pad "2" smd custom
			(at 0 0.4318)
			(size 0.127 0.127)
			(layers "B.Cu" "B.Mask" "B.Paste")
			(net "GBE_OBSN")
			(options
				(clearance outline)
				(anchor circle)
			)
			(primitives
				(gr_poly
					(pts
						(arc
							(start -0.2032 0.2794)
							(mid -0.239121 0.264521)
							(end -0.254 0.2286)
						)
						(arc
							(start -0.254 -0.2286)
							(mid -0.239121 -0.264521)
							(end -0.2032 -0.2794)
						)
						(arc
							(start 0.2032 -0.2794)
							(mid 0.239121 -0.264521)
							(end 0.254 -0.2286)
						)
						(arc
							(start 0.254 0.2286)
							(mid 0.239121 0.264521)
							(end 0.2032 0.2794)
						)
					)
					(width 0)
					(fill yes)
				)
			)
		)
	)
	(footprint ""
		(layer "B.Cu")
		(at 100.620068 -42.297096 180)
		(property "Reference" "C171"
			(at 0 0 0)
			(layer "B.SilkS")
			(hide yes)
			(effects
				(font
					(size 1.27 1.27)
				)
				(justify mirror)
			)
		)
		(property "Value" "SC1U10V2KX-1GP"
			(at -1.1811 -2.7051 180)
			(unlocked yes)
			(layer "B.Fab")
			(hide yes)
			(effects
				(font
					(size 1.016 1.016)
					(thickness 0.1524)
				)
				(justify mirror)
			)
		)
		(property "Device Type" "C402H22"
			(at -1.1811 -4.2291 180)
			(unlocked yes)
			(layer "B.Fab")
			(hide yes)
			(effects
				(font
					(size 1.016 1.016)
					(thickness 0.1524)
				)
				(justify mirror)
			)
		)
		(duplicate_pad_numbers_are_jumpers no)
		(fp_rect
			(start 0.381 0.7366)
			(end -0.381 -0.7366)
			(stroke
				(width 0)
				(type default)
			)
			(fill no)
			(layer "B.CrtYd")
		)
		(fp_rect
			(start 0.381 0.7366)
			(end -0.381 -0.7366)
			(stroke
				(width 0)
				(type default)
			)
			(fill no)
			(layer "B.Fab")
		)
		(pad "1" smd custom
			(at 0 -0.4572)
			(size 0.1143 0.1143)
			(layers "B.Cu" "B.Mask" "B.Paste")
			(net "PVNN")
			(options
				(clearance outline)
				(anchor circle)
			)
			(primitives
				(gr_poly
					(pts
						(arc
							(start -0.254 0.1778)
							(mid -0.239121 0.213721)
							(end -0.2032 0.2286)
						)
						(arc
							(start 0.2032 0.2286)
							(mid 0.239121 0.213721)
							(end 0.254 0.1778)
						)
						(arc
							(start 0.254 -0.1778)
							(mid 0.239121 -0.213721)
							(end 0.2032 -0.2286)
						)
						(arc
							(start -0.2032 -0.2286)
							(mid -0.239121 -0.213721)
							(end -0.254 -0.1778)
						)
					)
					(width 0)
					(fill yes)
				)
			)
		)
		(pad "2" smd custom
			(at 0 0.4572)
			(size 0.1143 0.1143)
			(layers "B.Cu" "B.Mask" "B.Paste")
			(net "GND")
			(options
				(clearance outline)
				(anchor circle)
			)
			(primitives
				(gr_poly
					(pts
						(arc
							(start -0.254 0.1778)
							(mid -0.239121 0.213721)
							(end -0.2032 0.2286)
						)
						(arc
							(start 0.2032 0.2286)
							(mid 0.239121 0.213721)
							(end 0.254 0.1778)
						)
						(arc
							(start 0.254 -0.1778)
							(mid 0.239121 -0.213721)
							(end 0.2032 -0.2286)
						)
						(arc
							(start -0.2032 -0.2286)
							(mid -0.239121 -0.213721)
							(end -0.254 -0.1778)
						)
					)
					(width 0)
					(fill yes)
				)
			)
		)
	)
	(footprint ""
		(layer "B.Cu")
		(at 151.765 -36.068 90)
		(property "Reference" "C233"
			(at 0 0 90)
			(layer "B.SilkS")
			(hide yes)
			(effects
				(font
					(size 1.27 1.27)
				)
				(justify mirror)
			)
		)
		(property "Value" "SCD1U10V2KX-5GP"
			(at -1.1811 -2.7051 90)
			(unlocked yes)
			(layer "B.Fab")
			(hide yes)
			(effects
				(font
					(size 1.016 1.016)
					(thickness 0.1524)
				)
				(justify mirror)
			)
		)
		(property "Device Type" "C402H22"
			(at -1.1811 -4.2291 90)
			(unlocked yes)
			(layer "B.Fab")
			(hide yes)
			(effects
				(font
					(size 1.016 1.016)
					(thickness 0.1524)
				)
				(justify mirror)
			)
		)
		(duplicate_pad_numbers_are_jumpers no)
		(fp_rect
			(start 0.381 0.7366)
			(end -0.381 -0.7366)
			(stroke
				(width 0)
				(type default)
			)
			(fill no)
			(layer "B.CrtYd")
		)
		(fp_rect
			(start 0.381 0.7366)
			(end -0.381 -0.7366)
			(stroke
				(width 0)
				(type default)
			)
			(fill no)
			(layer "B.Fab")
		)
		(pad "1" smd custom
			(at 0 -0.4572 270)
			(size 0.1143 0.1143)
			(layers "B.Cu" "B.Mask" "B.Paste")
			(net "P1V2_FPGA_D")
			(options
				(clearance outline)
				(anchor circle)
			)
			(primitives
				(gr_poly
					(pts
						(arc
							(start -0.254 0.1778)
							(mid -0.239121 0.213721)
							(end -0.2032 0.2286)
						)
						(arc
							(start 0.2032 0.2286)
							(mid 0.239121 0.213721)
							(end 0.254 0.1778)
						)
						(arc
							(start 0.254 -0.1778)
							(mid 0.239121 -0.213721)
							(end 0.2032 -0.2286)
						)
						(arc
							(start -0.2032 -0.2286)
							(mid -0.239121 -0.213721)
							(end -0.254 -0.1778)
						)
					)
					(width 0)
					(fill yes)
				)
			)
		)
		(pad "2" smd custom
			(at 0 0.4572 270)
			(size 0.1143 0.1143)
			(layers "B.Cu" "B.Mask" "B.Paste")
			(net "GND")
			(options
				(clearance outline)
				(anchor circle)
			)
			(primitives
				(gr_poly
					(pts
						(arc
							(start -0.254 0.1778)
							(mid -0.239121 0.213721)
							(end -0.2032 0.2286)
						)
						(arc
							(start 0.2032 0.2286)
							(mid 0.239121 0.213721)
							(end 0.254 0.1778)
						)
						(arc
							(start 0.254 -0.1778)
							(mid 0.239121 -0.213721)
							(end 0.2032 -0.2286)
						)
						(arc
							(start -0.2032 -0.2286)
							(mid -0.239121 -0.213721)
							(end -0.254 -0.1778)
						)
					)
					(width 0)
					(fill yes)
				)
			)
		)
	)
)
